# T6G (Grand Teton) — schematic netlist excerpt (pin names and nets, part order shuffled) for the footprints in the layout excerpt that follows; sources: Cadence DE-HDL packaged netlist, KiCad conversion of 04192023_DAF0TMB3IC0_F0TG_MB_C_brd_V02_OCP.brd

C2544  Q_CAP  22UF 4V 20% X6S  pkg C0402  page 70 : A = PVDDCR_SOC_P0 ; B = GND
R1209  Q_RES  0 5% CHIP  pkg 0201LF  page 186 : A = RST_SMB_RT_ROM_R1_N ; B = FM_SMB_RT_ROM_MUX8_SEL
R1371  Q_RES  4.7K 5% CHIP  pkg 0201LF  page 185 : A = P1V8_CPU0_RT_1D ; B = SMB_RT_CPU0_P1_ROM_MUX_2D_R_SDA

(kicad_pcb
	(version 20260206)
	(generator "pcbnew")
	(generator_version "10.0")
	(general
		(thickness 1.6)
		(legacy_teardrops no)
	)
	(paper "A4")
	(title_block
		(title "04192023_DAF0TMB3IC0_F0TG_MB_C_brd_V02_OCP.brd")
		(comment 1 "Grand Teton / footprints 5945-5947 of 8354")
	)
	(layers
		(0 "F.Cu" signal "TOP")
		(4 "In1.Cu" signal "GND")
		(6 "In2.Cu" signal "IN1")
		(8 "In3.Cu" signal "GND1")
		(10 "In4.Cu" signal "IN2")
		(12 "In5.Cu" signal "GND2")
		(14 "In6.Cu" signal "IN3")
		(16 "In7.Cu" signal "GND3")
		(18 "In8.Cu" signal "VCC")
		(20 "In9.Cu" signal "VCC1")
		(22 "In10.Cu" signal "GND4")
		(24 "In11.Cu" signal "IN4")
		(26 "In12.Cu" signal "GND5")
		(28 "In13.Cu" signal "IN5")
		(30 "In14.Cu" signal "GND6")
		(32 "In15.Cu" signal "IN6")
		(34 "In16.Cu" signal "GND7")
		(2 "B.Cu" signal "BOTTOM")
		(9 "F.Adhes" user "F.Adhesive")
		(11 "B.Adhes" user "B.Adhesive")
		(13 "F.Paste" user "Package Geometry/Pastemask Top")
		(15 "B.Paste" user "Package Geometry/Pastemask Bottom")
		(5 "F.SilkS" user "Ref Des/Silkscreen Top")
		(7 "B.SilkS" user "Ref Des/Silkscreen Bottom")
		(1 "F.Mask" user "Board Geometry/Soldermask Top")
		(3 "B.Mask" user "Board Geometry/Soldermask Bottom")
		(17 "Dwgs.User" user "User.Drawings")
		(19 "Cmts.User" user "User.Comments")
		(21 "Eco1.User" user "User.Eco1")
		(23 "Eco2.User" user "User.Eco2")
		(25 "Edge.Cuts" user "Board Geometry/Outline")
		(27 "Margin" user)
		(31 "F.CrtYd" user "Package Geometry/Place Bound Top")
		(29 "B.CrtYd" user "Package Geometry/Place Bound Bottom")
		(35 "F.Fab" user "Ref Des/Assembly Top")
		(33 "B.Fab" user "Ref Des/Assembly Bottom")
	)
	(footprint ""
		(layer "B.Cu")
		(at 369.62588 -257.930142)
		(property "Reference" "C2544"
			(at 0 0 0)
			(layer "B.SilkS")
			(hide yes)
			(effects
				(font
					(size 1.27 1.27)
				)
				(justify mirror)
			)
		)
		(property "Value" ""
			(at 0 0 0)
			(layer "B.Fab")
			(effects
				(font
					(size 1.27 1.27)
				)
				(justify mirror)
			)
		)
		(duplicate_pad_numbers_are_jumpers no)
		(fp_line
			(start -0.7874 -0.4064)
			(end -0.7874 0.4064)
			(stroke
				(width 0.1524)
				(type default)
			)
			(layer "B.SilkS")
		)
		(fp_line
			(start -0.7874 0.4064)
			(end 0.7874 0.4064)
			(stroke
				(width 0.1524)
				(type default)
			)
			(layer "B.SilkS")
		)
		(fp_line
			(start 0.7874 -0.4064)
			(end -0.7874 -0.4064)
			(stroke
				(width 0.1524)
				(type default)
			)
			(layer "B.SilkS")
		)
		(fp_line
			(start 0.7874 0.4064)
			(end 0.7874 -0.4064)
			(stroke
				(width 0.1524)
				(type default)
			)
			(layer "B.SilkS")
		)
		(fp_line
			(start -0.67945 -0.3048)
			(end -0.67945 0.3048)
			(stroke
				(width 0.1)
				(type default)
			)
			(layer "B.Fab")
		)
		(fp_line
			(start -0.67945 0.3048)
			(end -0.120396 0.3048)
			(stroke
				(width 0.1)
				(type default)
			)
			(layer "B.Fab")
		)
		(fp_line
			(start -0.12065 -0.3048)
			(end -0.67945 -0.3048)
			(stroke
				(width 0.1)
				(type default)
			)
			(layer "B.Fab")
		)
		(fp_line
			(start -0.12065 -0.2794)
			(end -0.12065 -0.3048)
			(stroke
				(width 0.1)
				(type default)
			)
			(layer "B.Fab")
		)
		(fp_line
			(start -0.120396 0.2794)
			(end 0.12065 0.2794)
			(stroke
				(width 0.1)
				(type default)
			)
			(layer "B.Fab")
		)
		(fp_line
			(start -0.120396 0.3048)
			(end -0.120396 0.2794)
			(stroke
				(width 0.1)
				(type default)
			)
			(layer "B.Fab")
		)
		(fp_line
			(start 0.12065 -0.305054)
			(end 0.12065 -0.2794)
			(stroke
				(width 0.1)
				(type default)
			)
			(layer "B.Fab")
		)
		(fp_line
			(start 0.12065 -0.2794)
			(end -0.12065 -0.2794)
			(stroke
				(width 0.1)
				(type default)
			)
			(layer "B.Fab")
		)
		(fp_line
			(start 0.12065 0.2794)
			(end 0.12065 0.3048)
			(stroke
				(width 0.1)
				(type default)
			)
			(layer "B.Fab")
		)
		(fp_line
			(start 0.12065 0.3048)
			(end 0.67945 0.3048)
			(stroke
				(width 0.1)
				(type default)
			)
			(layer "B.Fab")
		)
		(fp_line
			(start 0.67945 -0.305054)
			(end 0.12065 -0.305054)
			(stroke
				(width 0.1)
				(type default)
			)
			(layer "B.Fab")
		)
		(fp_line
			(start 0.67945 0.3048)
			(end 0.67945 -0.305054)
			(stroke
				(width 0.1)
				(type default)
			)
			(layer "B.Fab")
		)
		(pad "1" smd circle
			(at 0.40005 0 180)
			(size 0 0)
			(layers "B.Cu" "B.Mask" "B.Paste")
			(net "PVDDCR_SOC_P0")
		)
		(pad "2" smd circle
			(at -0.40005 0 180)
			(size 0 0)
			(layers "B.Cu" "B.Mask" "B.Paste")
			(net "GND")
		)
	)
	(footprint ""
		(layer "B.Cu")
		(at 254.635 -339.63864 180)
		(property "Reference" "R1371"
			(at 0 0 0)
			(layer "B.SilkS")
			(hide yes)
			(effects
				(font
					(size 1.27 1.27)
				)
				(justify mirror)
			)
		)
		(property "Value" ""
			(at 0 0 0)
			(layer "B.Fab")
			(effects
				(font
					(size 1.27 1.27)
				)
				(justify mirror)
			)
		)
		(duplicate_pad_numbers_are_jumpers no)
		(fp_line
			(start 0.32512 0.175006)
			(end 0.32512 -0.175006)
			(stroke
				(width 0.1)
				(type default)
			)
			(layer "B.Fab")
		)
		(fp_line
			(start 0.32512 -0.175006)
			(end -0.32512 -0.175006)
			(stroke
				(width 0.1)
				(type default)
			)
			(layer "B.Fab")
		)
		(fp_line
			(start -0.32512 0.175006)
			(end 0.32512 0.175006)
			(stroke
				(width 0.1)
				(type default)
			)
			(layer "B.Fab")
		)
		(fp_line
			(start -0.32512 -0.175006)
			(end -0.32512 0.175006)
			(stroke
				(width 0.1)
				(type default)
			)
			(layer "B.Fab")
		)
		(pad "1" smd rect
			(at 0.2667 0)
			(size 0.3048 0.381)
			(layers "B.Cu" "B.Mask" "B.Paste")
			(net "P1V8_CPU0_RT_1D")
		)
		(pad "2" smd rect
			(at -0.2667 0 180)
			(size 0.3048 0.381)
			(layers "B.Cu" "B.Mask" "B.Paste")
			(net "SMB_RT_CPU0_P1_ROM_MUX_2D_R_SDA")
		)
	)
	(footprint ""
		(layer "B.Cu")
		(at 418.998908 -428.682912 180)
		(property "Reference" "R1209"
			(at 0 0 0)
			(layer "B.SilkS")
			(hide yes)
			(effects
				(font
					(size 1.27 1.27)
				)
				(justify mirror)
			)
		)
		(property "Value" ""
			(at 0 0 0)
			(layer "B.Fab")
			(effects
				(font
					(size 1.27 1.27)
				)
				(justify mirror)
			)
		)
		(duplicate_pad_numbers_are_jumpers no)
		(fp_line
			(start 0.32512 0.175006)
			(end 0.32512 -0.175006)
			(stroke
				(width 0.1)
				(type default)
			)
			(layer "B.Fab")
		)
		(fp_line
			(start 0.32512 -0.175006)
			(end -0.32512 -0.175006)
			(stroke
				(width 0.1)
				(type default)
			)
			(layer "B.Fab")
		)
		(fp_line
			(start -0.32512 0.175006)
			(end 0.32512 0.175006)
			(stroke
				(width 0.1)
				(type default)
			)
			(layer "B.Fab")
		)
		(fp_line
			(start -0.32512 -0.175006)
			(end -0.32512 0.175006)
			(stroke
				(width 0.1)
				(type default)
			)
			(layer "B.Fab")
		)
		(pad "1" smd rect
			(at 0.2667 0)
			(size 0.3048 0.381)
			(layers "B.Cu" "B.Mask" "B.Paste")
			(net "RST_SMB_RT_ROM_R1_N")
		)
		(pad "2" smd rect
			(at -0.2667 0 180)
			(size 0.3048 0.381)
			(layers "B.Cu" "B.Mask" "B.Paste")
			(net "FM_SMB_RT_ROM_MUX8_SEL")
		)
	)
)
